(kicad_pcb
	(version 20260206)
	(generator "pcbnew")
	(generator_version "10.0")
	(general
		(thickness 1.6)
		(legacy_teardrops no)
	)
	(paper "A4")
	(title_block
		(title "01162023_DA0F0TEBIF0_F0T_Expander_BD_F_brd_V02_OCP.brd")
		(comment 1 "Grand Teton / footprints 9459-9467 of 9728")
	)
	(layers
		(0 "F.Cu" signal "TOP")
		(4 "In1.Cu" signal "GND")
		(6 "In2.Cu" signal "VCC")
		(8 "In3.Cu" signal "VCC1")
		(10 "In4.Cu" signal "GND1")
		(12 "In5.Cu" signal "IN1")
		(14 "In6.Cu" signal "GND2")
		(16 "In7.Cu" signal "IN2")
		(18 "In8.Cu" signal "GND3")
		(20 "In9.Cu" signal "IN3")
		(22 "In10.Cu" signal "GND4")
		(24 "In11.Cu" signal "IN4")
		(26 "In12.Cu" signal "GND5")
		(28 "In13.Cu" signal "IN5")
		(30 "In14.Cu" signal "GND6")
		(32 "In15.Cu" signal "IN6")
		(34 "In16.Cu" signal "GND7")
		(2 "B.Cu" signal "BOTTOM")
		(9 "F.Adhes" user "F.Adhesive")
		(11 "B.Adhes" user "B.Adhesive")
		(13 "F.Paste" user "Package Geometry/Pastemask Top")
		(15 "B.Paste" user "Package Geometry/Pastemask Bottom")
		(5 "F.SilkS" user "Ref Des/Silkscreen Top")
		(7 "B.SilkS" user "Ref Des/Silkscreen Bottom")
		(1 "F.Mask" user "Board Geometry/Soldermask Top")
		(3 "B.Mask" user "Board Geometry/Soldermask Bottom")
		(17 "Dwgs.User" user "User.Drawings")
		(19 "Cmts.User" user "User.Comments")
		(21 "Eco1.User" user "User.Eco1")
		(23 "Eco2.User" user "User.Eco2")
		(25 "Edge.Cuts" user "Board Geometry/Outline")
		(27 "Margin" user)
		(31 "F.CrtYd" user "Package Geometry/Place Bound Top")
		(29 "B.CrtYd" user "Package Geometry/Place Bound Bottom")
		(35 "F.Fab" user "Ref Des/Assembly Top")
		(33 "B.Fab" user "Ref Des/Assembly Bottom")
	)
	(footprint ""
		(layer "B.Cu")
		(at 210.782408 -225.68027 -90)
		(property "Reference" "C4491"
			(at 0 0 90)
			(layer "B.SilkS")
			(hide yes)
			(effects
				(font
					(size 1.27 1.27)
				)
				(justify mirror)
			)
		)
		(property "Value" ""
			(at 0 0 90)
			(layer "B.Fab")
			(effects
				(font
					(size 1.27 1.27)
				)
				(justify mirror)
			)
		)
		(duplicate_pad_numbers_are_jumpers no)
		(fp_line
			(start -0.7874 0.4064)
			(end 0.7874 0.4064)
			(stroke
				(width 0.1524)
				(type default)
			)
			(layer "B.SilkS")
		)
		(fp_line
			(start 0.7874 0.4064)
			(end 0.7874 -0.4064)
			(stroke
				(width 0.1524)
				(type default)
			)
			(layer "B.SilkS")
		)
		(fp_line
			(start -0.7874 -0.4064)
			(end -0.7874 0.4064)
			(stroke
				(width 0.1524)
				(type default)
			)
			(layer "B.SilkS")
		)
		(fp_line
			(start 0.7874 -0.4064)
			(end -0.7874 -0.4064)
			(stroke
				(width 0.1524)
				(type default)
			)
			(layer "B.SilkS")
		)
		(fp_line
			(start -0.67945 0.3048)
			(end -0.120396 0.3048)
			(stroke
				(width 0.1)
				(type default)
			)
			(layer "B.Fab")
		)
		(fp_line
			(start -0.120396 0.3048)
			(end -0.120396 0.2794)
			(stroke
				(width 0.1)
				(type default)
			)
			(layer "B.Fab")
		)
		(fp_line
			(start 0.12065 0.3048)
			(end 0.67945 0.3048)
			(stroke
				(width 0.1)
				(type default)
			)
			(layer "B.Fab")
		)
		(fp_line
			(start 0.67945 0.3048)
			(end 0.67945 -0.305054)
			(stroke
				(width 0.1)
				(type default)
			)
			(layer "B.Fab")
		)
		(fp_line
			(start -0.120396 0.2794)
			(end 0.12065 0.2794)
			(stroke
				(width 0.1)
				(type default)
			)
			(layer "B.Fab")
		)
		(fp_line
			(start 0.12065 0.2794)
			(end 0.12065 0.3048)
			(stroke
				(width 0.1)
				(type default)
			)
			(layer "B.Fab")
		)
		(fp_line
			(start -0.12065 -0.2794)
			(end -0.12065 -0.3048)
			(stroke
				(width 0.1)
				(type default)
			)
			(layer "B.Fab")
		)
		(fp_line
			(start 0.12065 -0.2794)
			(end -0.12065 -0.2794)
			(stroke
				(width 0.1)
				(type default)
			)
			(layer "B.Fab")
		)
		(fp_line
			(start -0.67945 -0.3048)
			(end -0.67945 0.3048)
			(stroke
				(width 0.1)
				(type default)
			)
			(layer "B.Fab")
		)
		(fp_line
			(start -0.12065 -0.3048)
			(end -0.67945 -0.3048)
			(stroke
				(width 0.1)
				(type default)
			)
			(layer "B.Fab")
		)
		(fp_line
			(start 0.12065 -0.305054)
			(end 0.12065 -0.2794)
			(stroke
				(width 0.1)
				(type default)
			)
			(layer "B.Fab")
		)
		(fp_line
			(start 0.67945 -0.305054)
			(end 0.12065 -0.305054)
			(stroke
				(width 0.1)
				(type default)
			)
			(layer "B.Fab")
		)
		(pad "1" smd circle
			(at 0.40005 0 90)
			(size 0 0)
			(layers "B.Cu" "B.Mask" "B.Paste")
			(net "ADC_TYPE_ADC_R")
		)
		(pad "2" smd circle
			(at -0.40005 0 90)
			(size 0 0)
			(layers "B.Cu" "B.Mask" "B.Paste")
			(net "GND")
		)
	)
	(footprint ""
		(layer "B.Cu")
		(at 281.608022 -303.024794 180)
		(property "Reference" "C3360"
			(at 0 0 0)
			(layer "B.SilkS")
			(hide yes)
			(effects
				(font
					(size 1.27 1.27)
				)
				(justify mirror)
			)
		)
		(property "Value" ""
			(at 0 0 0)
			(layer "B.Fab")
			(effects
				(font
					(size 1.27 1.27)
				)
				(justify mirror)
			)
		)
		(duplicate_pad_numbers_are_jumpers no)
		(fp_line
			(start 0.299974 0.150114)
			(end 0.299974 -0.150114)
			(stroke
				(width 0.1)
				(type default)
			)
			(layer "B.Fab")
		)
		(fp_line
			(start 0.299974 -0.150114)
			(end -0.299974 -0.150114)
			(stroke
				(width 0.1)
				(type default)
			)
			(layer "B.Fab")
		)
		(fp_line
			(start -0.299974 0.150114)
			(end 0.299974 0.150114)
			(stroke
				(width 0.1)
				(type default)
			)
			(layer "B.Fab")
		)
		(fp_line
			(start -0.299974 -0.150114)
			(end -0.299974 0.150114)
			(stroke
				(width 0.1)
				(type default)
			)
			(layer "B.Fab")
		)
		(pad "1" smd rect
			(at 0.2667 0)
			(size 0.3048 0.381)
			(layers "B.Cu" "B.Mask" "B.Paste")
			(net "P1V8_VDDA_PEX2")
		)
		(pad "2" smd rect
			(at -0.2667 0)
			(size 0.3048 0.381)
			(layers "B.Cu" "B.Mask" "B.Paste")
			(net "GND")
		)
	)
	(footprint ""
		(layer "B.Cu")
		(at 283.720032 -305.399948 -90)
		(property "Reference" "C3326"
			(at 0 0 90)
			(layer "B.SilkS")
			(hide yes)
			(effects
				(font
					(size 1.27 1.27)
				)
				(justify mirror)
			)
		)
		(property "Value" ""
			(at 0 0 90)
			(layer "B.Fab")
			(effects
				(font
					(size 1.27 1.27)
				)
				(justify mirror)
			)
		)
		(duplicate_pad_numbers_are_jumpers no)
		(fp_line
			(start -0.299974 0.150114)
			(end 0.299974 0.150114)
			(stroke
				(width 0.1)
				(type default)
			)
			(layer "B.Fab")
		)
		(fp_line
			(start 0.299974 0.150114)
			(end 0.299974 -0.150114)
			(stroke
				(width 0.1)
				(type default)
			)
			(layer "B.Fab")
		)
		(fp_line
			(start -0.299974 -0.150114)
			(end -0.299974 0.150114)
			(stroke
				(width 0.1)
				(type default)
			)
			(layer "B.Fab")
		)
		(fp_line
			(start 0.299974 -0.150114)
			(end -0.299974 -0.150114)
			(stroke
				(width 0.1)
				(type default)
			)
			(layer "B.Fab")
		)
		(pad "1" smd rect
			(at 0.2667 0 90)
			(size 0.3048 0.381)
			(layers "B.Cu" "B.Mask" "B.Paste")
			(net "P1V25_SERDES_VDDPLL_PEX2")
		)
		(pad "2" smd rect
			(at -0.2667 0 90)
			(size 0.3048 0.381)
			(layers "B.Cu" "B.Mask" "B.Paste")
			(net "GND")
		)
	)
	(footprint ""
		(layer "B.Cu")
		(at 296.599864 -299.699934 -90)
		(property "Reference" "C1722"
			(at 0 0 90)
			(layer "B.SilkS")
			(hide yes)
			(effects
				(font
					(size 1.27 1.27)
				)
				(justify mirror)
			)
		)
		(property "Value" ""
			(at 0 0 90)
			(layer "B.Fab")
			(effects
				(font
					(size 1.27 1.27)
				)
				(justify mirror)
			)
		)
		(duplicate_pad_numbers_are_jumpers no)
		(fp_line
			(start -0.299974 0.150114)
			(end 0.299974 0.150114)
			(stroke
				(width 0.1)
				(type default)
			)
			(layer "B.Fab")
		)
		(fp_line
			(start 0.299974 0.150114)
			(end 0.299974 -0.150114)
			(stroke
				(width 0.1)
				(type default)
			)
			(layer "B.Fab")
		)
		(fp_line
			(start -0.299974 -0.150114)
			(end -0.299974 0.150114)
			(stroke
				(width 0.1)
				(type default)
			)
			(layer "B.Fab")
		)
		(fp_line
			(start 0.299974 -0.150114)
			(end -0.299974 -0.150114)
			(stroke
				(width 0.1)
				(type default)
			)
			(layer "B.Fab")
		)
		(pad "1" smd rect
			(at 0.2667 0 90)
			(size 0.3048 0.381)
			(layers "B.Cu" "B.Mask" "B.Paste")
			(net "P0V8_SERDES_VDDA_PEX2")
		)
		(pad "2" smd rect
			(at -0.2667 0 90)
			(size 0.3048 0.381)
			(layers "B.Cu" "B.Mask" "B.Paste")
			(net "GND")
		)
	)
	(footprint ""
		(layer "B.Cu")
		(at 64.399922 -303.499774 -90)
		(property "Reference" "C2939"
			(at 0 0 90)
			(layer "B.SilkS")
			(hide yes)
			(effects
				(font
					(size 1.27 1.27)
				)
				(justify mirror)
			)
		)
		(property "Value" ""
			(at 0 0 90)
			(layer "B.Fab")
			(effects
				(font
					(size 1.27 1.27)
				)
				(justify mirror)
			)
		)
		(duplicate_pad_numbers_are_jumpers no)
		(fp_line
			(start -0.299974 0.150114)
			(end 0.299974 0.150114)
			(stroke
				(width 0.1)
				(type default)
			)
			(layer "B.Fab")
		)
		(fp_line
			(start 0.299974 0.150114)
			(end 0.299974 -0.150114)
			(stroke
				(width 0.1)
				(type default)
			)
			(layer "B.Fab")
		)
		(fp_line
			(start -0.299974 -0.150114)
			(end -0.299974 0.150114)
			(stroke
				(width 0.1)
				(type default)
			)
			(layer "B.Fab")
		)
		(fp_line
			(start 0.299974 -0.150114)
			(end -0.299974 -0.150114)
			(stroke
				(width 0.1)
				(type default)
			)
			(layer "B.Fab")
		)
		(pad "1" smd rect
			(at 0.2667 0 90)
			(size 0.3048 0.381)
			(layers "B.Cu" "B.Mask" "B.Paste")
			(net "P1V25_PEX0")
		)
		(pad "2" smd rect
			(at -0.2667 0 90)
			(size 0.3048 0.381)
			(layers "B.Cu" "B.Mask" "B.Paste")
			(net "GND")
		)
	)
	(footprint ""
		(layer "B.Cu")
		(at 417.924996 -304.241454 90)
		(property "Reference" "C3529"
			(at 0 0 90)
			(layer "B.SilkS")
			(hide yes)
			(effects
				(font
					(size 1.27 1.27)
				)
				(justify mirror)
			)
		)
		(property "Value" ""
			(at 0 0 90)
			(layer "B.Fab")
			(effects
				(font
					(size 1.27 1.27)
				)
				(justify mirror)
			)
		)
		(duplicate_pad_numbers_are_jumpers no)
		(fp_line
			(start 0.299974 -0.150114)
			(end -0.299974 -0.150114)
			(stroke
				(width 0.1)
				(type default)
			)
			(layer "B.Fab")
		)
		(fp_line
			(start -0.299974 -0.150114)
			(end -0.299974 0.150114)
			(stroke
				(width 0.1)
				(type default)
			)
			(layer "B.Fab")
		)
		(fp_line
			(start 0.299974 0.150114)
			(end 0.299974 -0.150114)
			(stroke
				(width 0.1)
				(type default)
			)
			(layer "B.Fab")
		)
		(fp_line
			(start -0.299974 0.150114)
			(end 0.299974 0.150114)
			(stroke
				(width 0.1)
				(type default)
			)
			(layer "B.Fab")
		)
		(pad "1" smd rect
			(at 0.2667 0 270)
			(size 0.3048 0.381)
			(layers "B.Cu" "B.Mask" "B.Paste")
			(net "P1V8_VDDA_PEX3")
		)
		(pad "2" smd rect
			(at -0.2667 0 270)
			(size 0.3048 0.381)
			(layers "B.Cu" "B.Mask" "B.Paste")
			(net "GND")
		)
	)
	(footprint ""
		(layer "B.Cu")
		(at 109.502956 -325.22414 -90)
		(property "Reference" "C4214"
			(at 0 0 90)
			(layer "B.SilkS")
			(hide yes)
			(effects
				(font
					(size 1.27 1.27)
				)
				(justify mirror)
			)
		)
		(property "Value" ""
			(at 0 0 90)
			(layer "B.Fab")
			(effects
				(font
					(size 1.27 1.27)
				)
				(justify mirror)
			)
		)
		(duplicate_pad_numbers_are_jumpers no)
		(fp_line
			(start -1.2954 0.5842)
			(end 1.2954 0.5842)
			(stroke
				(width 0.1524)
				(type default)
			)
			(layer "B.SilkS")
		)
		(fp_line
			(start 1.2954 0.5842)
			(end 1.2954 -0.5842)
			(stroke
				(width 0.1524)
				(type default)
			)
			(layer "B.SilkS")
		)
		(fp_line
			(start -1.2954 -0.5842)
			(end -1.2954 0.5842)
			(stroke
				(width 0.1524)
				(type default)
			)
			(layer "B.SilkS")
		)
		(fp_line
			(start 1.2954 -0.5842)
			(end -1.2954 -0.5842)
			(stroke
				(width 0.1524)
				(type default)
			)
			(layer "B.SilkS")
		)
		(fp_line
			(start -0.8636 0.4572)
			(end 0.8636 0.4572)
			(stroke
				(width 0.1)
				(type default)
			)
			(layer "B.Fab")
		)
		(fp_line
			(start 0.8636 0.4572)
			(end 0.8636 0.4064)
			(stroke
				(width 0.1)
				(type default)
			)
			(layer "B.Fab")
		)
		(fp_line
			(start -1.1938 0.4064)
			(end -0.8636 0.4064)
			(stroke
				(width 0.1)
				(type default)
			)
			(layer "B.Fab")
		)
		(fp_line
			(start -0.8636 0.4064)
			(end -0.8636 0.4572)
			(stroke
				(width 0.1)
				(type default)
			)
			(layer "B.Fab")
		)
		(fp_line
			(start 0.8636 0.4064)
			(end 1.1938 0.4064)
			(stroke
				(width 0.1)
				(type default)
			)
			(layer "B.Fab")
		)
		(fp_line
			(start 1.1938 0.4064)
			(end 1.1938 -0.4064)
			(stroke
				(width 0.1)
				(type default)
			)
			(layer "B.Fab")
		)
		(fp_line
			(start -1.1938 -0.4064)
			(end -1.1938 0.4064)
			(stroke
				(width 0.1)
				(type default)
			)
			(layer "B.Fab")
		)
		(fp_line
			(start -0.8636 -0.4064)
			(end -1.1938 -0.4064)
			(stroke
				(width 0.1)
				(type default)
			)
			(layer "B.Fab")
		)
		(fp_line
			(start 0.8636 -0.4064)
			(end 0.8636 -0.4572)
			(stroke
				(width 0.1)
				(type default)
			)
			(layer "B.Fab")
		)
		(fp_line
			(start 1.1938 -0.4064)
			(end 0.8636 -0.4064)
			(stroke
				(width 0.1)
				(type default)
			)
			(layer "B.Fab")
		)
		(fp_line
			(start -0.8636 -0.4572)
			(end -0.8636 -0.4064)
			(stroke
				(width 0.1)
				(type default)
			)
			(layer "B.Fab")
		)
		(fp_line
			(start 0.8636 -0.4572)
			(end -0.8636 -0.4572)
			(stroke
				(width 0.1)
				(type default)
			)
			(layer "B.Fab")
		)
		(pad "1" smd rect
			(at 0.7366 0 180)
			(size 0.7112 0.8128)
			(layers "B.Cu" "B.Mask" "B.Paste")
			(net "P0V8_SERDES_VDDA_PEX0_C8")
		)
		(pad "2" smd rect
			(at -0.7366 0 180)
			(size 0.7112 0.8128)
			(layers "B.Cu" "B.Mask" "B.Paste")
			(net "GND")
		)
	)
	(footprint ""
		(layer "B.Cu")
		(at 3.06578 -275.977858)
		(property "Reference" "C4234"
			(at 0 0 0)
			(layer "B.SilkS")
			(hide yes)
			(effects
				(font
					(size 1.27 1.27)
				)
				(justify mirror)
			)
		)
		(property "Value" ""
			(at 0 0 0)
			(layer "B.Fab")
			(effects
				(font
					(size 1.27 1.27)
				)
				(justify mirror)
			)
		)
		(duplicate_pad_numbers_are_jumpers no)
		(fp_line
			(start -1.2954 -0.5842)
			(end -1.2954 0.5842)
			(stroke
				(width 0.1524)
				(type default)
			)
			(layer "B.SilkS")
		)
		(fp_line
			(start -1.2954 0.5842)
			(end 1.2954 0.5842)
			(stroke
				(width 0.1524)
				(type default)
			)
			(layer "B.SilkS")
		)
		(fp_line
			(start 1.2954 -0.5842)
			(end -1.2954 -0.5842)
			(stroke
				(width 0.1524)
				(type default)
			)
			(layer "B.SilkS")
		)
		(fp_line
			(start 1.2954 0.5842)
			(end 1.2954 -0.5842)
			(stroke
				(width 0.1524)
				(type default)
			)
			(layer "B.SilkS")
		)
		(fp_line
			(start -1.1938 -0.4064)
			(end -1.1938 0.4064)
			(stroke
				(width 0.1)
				(type default)
			)
			(layer "B.Fab")
		)
		(fp_line
			(start -1.1938 0.4064)
			(end -0.8636 0.4064)
			(stroke
				(width 0.1)
				(type default)
			)
			(layer "B.Fab")
		)
		(fp_line
			(start -0.8636 -0.4572)
			(end -0.8636 -0.4064)
			(stroke
				(width 0.1)
				(type default)
			)
			(layer "B.Fab")
		)
		(fp_line
			(start -0.8636 -0.4064)
			(end -1.1938 -0.4064)
			(stroke
				(width 0.1)
				(type default)
			)
			(layer "B.Fab")
		)
		(fp_line
			(start -0.8636 0.4064)
			(end -0.8636 0.4572)
			(stroke
				(width 0.1)
				(type default)
			)
			(layer "B.Fab")
		)
		(fp_line
			(start -0.8636 0.4572)
			(end 0.8636 0.4572)
			(stroke
				(width 0.1)
				(type default)
			)
			(layer "B.Fab")
		)
		(fp_line
			(start 0.8636 -0.4572)
			(end -0.8636 -0.4572)
			(stroke
				(width 0.1)
				(type default)
			)
			(layer "B.Fab")
		)
		(fp_line
			(start 0.8636 -0.4064)
			(end 0.8636 -0.4572)
			(stroke
				(width 0.1)
				(type default)
			)
			(layer "B.Fab")
		)
		(fp_line
			(start 0.8636 0.4064)
			(end 1.1938 0.4064)
			(stroke
				(width 0.1)
				(type default)
			)
			(layer "B.Fab")
		)
		(fp_line
			(start 0.8636 0.4572)
			(end 0.8636 0.4064)
			(stroke
				(width 0.1)
				(type default)
			)
			(layer "B.Fab")
		)
		(fp_line
			(start 1.1938 -0.4064)
			(end 0.8636 -0.4064)
			(stroke
				(width 0.1)
				(type default)
			)
			(layer "B.Fab")
		)
		(fp_line
			(start 1.1938 0.4064)
			(end 1.1938 -0.4064)
			(stroke
				(width 0.1)
				(type default)
			)
			(layer "B.Fab")
		)
		(pad "1" smd rect
			(at 0.7366 0 270)
			(size 0.7112 0.8128)
			(layers "B.Cu" "B.Mask" "B.Paste")
			(net "P1V25_PEX0")
		)
		(pad "2" smd rect
			(at -0.7366 0 270)
			(size 0.7112 0.8128)
			(layers "B.Cu" "B.Mask" "B.Paste")
			(net "GND")
		)
	)
	(footprint ""
		(layer "B.Cu")
		(at 211.569808 -239.851692 90)
		(property "Reference" "R1546"
			(at 0 0 90)
			(layer "B.SilkS")
			(hide yes)
			(effects
				(font
					(size 1.27 1.27)
				)
				(justify mirror)
			)
		)
		(property "Value" ""
			(at 0 0 90)
			(layer "B.Fab")
			(effects
				(font
					(size 1.27 1.27)
				)
				(justify mirror)
			)
		)
		(duplicate_pad_numbers_are_jumpers no)
		(fp_line
			(start 0.7874 -0.4064)
			(end -0.7874 -0.4064)
			(stroke
				(width 0.1524)
				(type default)
			)
			(layer "B.SilkS")
		)
		(fp_line
			(start -0.7874 -0.4064)
			(end -0.7874 0.4064)
			(stroke
				(width 0.1524)
				(type default)
			)
			(layer "B.SilkS")
		)
		(fp_line
			(start 0.7874 0.4064)
			(end 0.7874 -0.4064)
			(stroke
				(width 0.1524)
				(type default)
			)
			(layer "B.SilkS")
		)
		(fp_line
			(start -0.7874 0.4064)
			(end 0.7874 0.4064)
			(stroke
				(width 0.1524)
				(type default)
			)
			(layer "B.SilkS")
		)
		(fp_line
			(start 0.67945 -0.305054)
			(end 0.12065 -0.305054)
			(stroke
				(width 0.1)
				(type default)
			)
			(layer "B.Fab")
		)
		(fp_line
			(start 0.12065 -0.305054)
			(end 0.12065 -0.2794)
			(stroke
				(width 0.1)
				(type default)
			)
			(layer "B.Fab")
		)
		(fp_line
			(start -0.12065 -0.3048)
			(end -0.67945 -0.3048)
			(stroke
				(width 0.1)
				(type default)
			)
			(layer "B.Fab")
		)
		(fp_line
			(start -0.67945 -0.3048)
			(end -0.67945 0.3048)
			(stroke
				(width 0.1)
				(type default)
			)
			(layer "B.Fab")
		)
		(fp_line
			(start 0.12065 -0.2794)
			(end -0.12065 -0.2794)
			(stroke
				(width 0.1)
				(type default)
			)
			(layer "B.Fab")
		)
		(fp_line
			(start -0.12065 -0.2794)
			(end -0.12065 -0.3048)
			(stroke
				(width 0.1)
				(type default)
			)
			(layer "B.Fab")
		)
		(fp_line
			(start 0.12065 0.2794)
			(end 0.12065 0.3048)
			(stroke
				(width 0.1)
				(type default)
			)
			(layer "B.Fab")
		)
		(fp_line
			(start -0.120396 0.2794)
			(end 0.12065 0.2794)
			(stroke
				(width 0.1)
				(type default)
			)
			(layer "B.Fab")
		)
		(fp_line
			(start 0.67945 0.3048)
			(end 0.67945 -0.305054)
			(stroke
				(width 0.1)
				(type default)
			)
			(layer "B.Fab")
		)
		(fp_line
			(start 0.12065 0.3048)
			(end 0.67945 0.3048)
			(stroke
				(width 0.1)
				(type default)
			)
			(layer "B.Fab")
		)
		(fp_line
			(start -0.120396 0.3048)
			(end -0.120396 0.2794)
			(stroke
				(width 0.1)
				(type default)
			)
			(layer "B.Fab")
		)
		(fp_line
			(start -0.67945 0.3048)
			(end -0.120396 0.3048)
			(stroke
				(width 0.1)
				(type default)
			)
			(layer "B.Fab")
		)
		(pad "1" smd circle
			(at 0.40005 0 270)
			(size 0 0)
			(layers "B.Cu" "B.Mask" "B.Paste")
			(net "SMB_PEX_R_SCL")
		)
		(pad "2" smd circle
			(at -0.40005 0 270)
			(size 0 0)
			(layers "B.Cu" "B.Mask" "B.Paste")
			(net "SMB_PEX_LS_SCL")
		)
	)
)
